(kicad_pcb
	(version 20260206)
	(generator "pcbnew")
	(generator_version "10.0")
	(general
		(thickness 1.6)
		(legacy_teardrops no)
	)
	(paper "A4")
	(title_block
		(title "12092022_DA0F0TMDCD0_F0T_Management_Board_D_brd_V3_OCP.brd")
		(comment 1 "Grand Teton / footprints 1023-1028 of 1440")
	)
	(layers
		(0 "F.Cu" signal "TOP")
		(4 "In1.Cu" signal "GND")
		(6 "In2.Cu" signal "IN1")
		(8 "In3.Cu" signal "GND1")
		(10 "In4.Cu" signal "IN2")
		(12 "In5.Cu" signal "VCC")
		(14 "In6.Cu" signal "VCC1")
		(16 "In7.Cu" signal "IN3")
		(18 "In8.Cu" signal "GND2")
		(20 "In9.Cu" signal "IN4")
		(22 "In10.Cu" signal "GND3")
		(2 "B.Cu" signal "BOTTOM")
		(9 "F.Adhes" user "F.Adhesive")
		(11 "B.Adhes" user "B.Adhesive")
		(13 "F.Paste" user "Package Geometry/Pastemask Top")
		(15 "B.Paste" user "Package Geometry/Pastemask Bottom")
		(5 "F.SilkS" user "Ref Des/Silkscreen Top")
		(7 "B.SilkS" user "Ref Des/Silkscreen Bottom")
		(1 "F.Mask" user "Board Geometry/Soldermask Top")
		(3 "B.Mask" user "Board Geometry/Soldermask Bottom")
		(17 "Dwgs.User" user "User.Drawings")
		(19 "Cmts.User" user "User.Comments")
		(21 "Eco1.User" user "User.Eco1")
		(23 "Eco2.User" user "User.Eco2")
		(25 "Edge.Cuts" user "Board Geometry/Outline")
		(27 "Margin" user)
		(31 "F.CrtYd" user "Package Geometry/Place Bound Top")
		(29 "B.CrtYd" user "Package Geometry/Place Bound Bottom")
		(35 "F.Fab" user "Ref Des/Assembly Top")
		(33 "B.Fab" user "Ref Des/Assembly Bottom")
	)
	(footprint ""
		(layer "B.Cu")
		(at 12.319 -88.392 180)
		(property "Reference" "R833"
			(at 0 0 0)
			(layer "B.SilkS")
			(hide yes)
			(effects
				(font
					(size 1.27 1.27)
				)
				(justify mirror)
			)
		)
		(property "Value" ""
			(at 0 0 0)
			(layer "B.Fab")
			(effects
				(font
					(size 1.27 1.27)
				)
				(justify mirror)
			)
		)
		(duplicate_pad_numbers_are_jumpers no)
		(fp_line
			(start 0.7874 0.4064)
			(end 0.7874 -0.4064)
			(stroke
				(width 0.1524)
				(type default)
			)
			(layer "B.SilkS")
		)
		(fp_line
			(start 0.7874 -0.4064)
			(end -0.7874 -0.4064)
			(stroke
				(width 0.1524)
				(type default)
			)
			(layer "B.SilkS")
		)
		(fp_line
			(start -0.7874 0.4064)
			(end 0.7874 0.4064)
			(stroke
				(width 0.1524)
				(type default)
			)
			(layer "B.SilkS")
		)
		(fp_line
			(start -0.7874 -0.4064)
			(end -0.7874 0.4064)
			(stroke
				(width 0.1524)
				(type default)
			)
			(layer "B.SilkS")
		)
		(fp_line
			(start 0.67945 0.3048)
			(end 0.67945 -0.305054)
			(stroke
				(width 0.1)
				(type default)
			)
			(layer "B.Fab")
		)
		(fp_line
			(start 0.67945 -0.305054)
			(end 0.12065 -0.305054)
			(stroke
				(width 0.1)
				(type default)
			)
			(layer "B.Fab")
		)
		(fp_line
			(start 0.12065 0.3048)
			(end 0.67945 0.3048)
			(stroke
				(width 0.1)
				(type default)
			)
			(layer "B.Fab")
		)
		(fp_line
			(start 0.12065 0.2794)
			(end 0.12065 0.3048)
			(stroke
				(width 0.1)
				(type default)
			)
			(layer "B.Fab")
		)
		(fp_line
			(start 0.12065 -0.2794)
			(end -0.12065 -0.2794)
			(stroke
				(width 0.1)
				(type default)
			)
			(layer "B.Fab")
		)
		(fp_line
			(start 0.12065 -0.305054)
			(end 0.12065 -0.2794)
			(stroke
				(width 0.1)
				(type default)
			)
			(layer "B.Fab")
		)
		(fp_line
			(start -0.120396 0.3048)
			(end -0.120396 0.2794)
			(stroke
				(width 0.1)
				(type default)
			)
			(layer "B.Fab")
		)
		(fp_line
			(start -0.120396 0.2794)
			(end 0.12065 0.2794)
			(stroke
				(width 0.1)
				(type default)
			)
			(layer "B.Fab")
		)
		(fp_line
			(start -0.12065 -0.2794)
			(end -0.12065 -0.3048)
			(stroke
				(width 0.1)
				(type default)
			)
			(layer "B.Fab")
		)
		(fp_line
			(start -0.12065 -0.3048)
			(end -0.67945 -0.3048)
			(stroke
				(width 0.1)
				(type default)
			)
			(layer "B.Fab")
		)
		(fp_line
			(start -0.67945 0.3048)
			(end -0.120396 0.3048)
			(stroke
				(width 0.1)
				(type default)
			)
			(layer "B.Fab")
		)
		(fp_line
			(start -0.67945 -0.3048)
			(end -0.67945 0.3048)
			(stroke
				(width 0.1)
				(type default)
			)
			(layer "B.Fab")
		)
		(pad "1" smd circle
			(at 0.40005 0)
			(size 0 0)
			(layers "B.Cu" "B.Mask" "B.Paste")
			(net "FM_ESPI_PLD_EN")
		)
		(pad "2" smd circle
			(at -0.40005 0)
			(size 0 0)
			(layers "B.Cu" "B.Mask" "B.Paste")
			(net "FM_ESPI_PLD_R_EN")
		)
	)
	(footprint ""
		(layer "B.Cu")
		(at 60.7314 -64.0588 -90)
		(property "Reference" "R725"
			(at 0 0 90)
			(layer "B.SilkS")
			(hide yes)
			(effects
				(font
					(size 1.27 1.27)
				)
				(justify mirror)
			)
		)
		(property "Value" ""
			(at 0 0 90)
			(layer "B.Fab")
			(effects
				(font
					(size 1.27 1.27)
				)
				(justify mirror)
			)
		)
		(duplicate_pad_numbers_are_jumpers no)
		(fp_line
			(start -0.7874 0.4064)
			(end 0.7874 0.4064)
			(stroke
				(width 0.1524)
				(type default)
			)
			(layer "B.SilkS")
		)
		(fp_line
			(start 0.7874 0.4064)
			(end 0.7874 -0.4064)
			(stroke
				(width 0.1524)
				(type default)
			)
			(layer "B.SilkS")
		)
		(fp_line
			(start -0.7874 -0.4064)
			(end -0.7874 0.4064)
			(stroke
				(width 0.1524)
				(type default)
			)
			(layer "B.SilkS")
		)
		(fp_line
			(start 0.7874 -0.4064)
			(end -0.7874 -0.4064)
			(stroke
				(width 0.1524)
				(type default)
			)
			(layer "B.SilkS")
		)
		(fp_line
			(start -0.67945 0.3048)
			(end -0.120396 0.3048)
			(stroke
				(width 0.1)
				(type default)
			)
			(layer "B.Fab")
		)
		(fp_line
			(start -0.120396 0.3048)
			(end -0.120396 0.2794)
			(stroke
				(width 0.1)
				(type default)
			)
			(layer "B.Fab")
		)
		(fp_line
			(start 0.12065 0.3048)
			(end 0.67945 0.3048)
			(stroke
				(width 0.1)
				(type default)
			)
			(layer "B.Fab")
		)
		(fp_line
			(start 0.67945 0.3048)
			(end 0.67945 -0.305054)
			(stroke
				(width 0.1)
				(type default)
			)
			(layer "B.Fab")
		)
		(fp_line
			(start -0.120396 0.2794)
			(end 0.12065 0.2794)
			(stroke
				(width 0.1)
				(type default)
			)
			(layer "B.Fab")
		)
		(fp_line
			(start 0.12065 0.2794)
			(end 0.12065 0.3048)
			(stroke
				(width 0.1)
				(type default)
			)
			(layer "B.Fab")
		)
		(fp_line
			(start -0.12065 -0.2794)
			(end -0.12065 -0.3048)
			(stroke
				(width 0.1)
				(type default)
			)
			(layer "B.Fab")
		)
		(fp_line
			(start 0.12065 -0.2794)
			(end -0.12065 -0.2794)
			(stroke
				(width 0.1)
				(type default)
			)
			(layer "B.Fab")
		)
		(fp_line
			(start -0.67945 -0.3048)
			(end -0.67945 0.3048)
			(stroke
				(width 0.1)
				(type default)
			)
			(layer "B.Fab")
		)
		(fp_line
			(start -0.12065 -0.3048)
			(end -0.67945 -0.3048)
			(stroke
				(width 0.1)
				(type default)
			)
			(layer "B.Fab")
		)
		(fp_line
			(start 0.12065 -0.305054)
			(end 0.12065 -0.2794)
			(stroke
				(width 0.1)
				(type default)
			)
			(layer "B.Fab")
		)
		(fp_line
			(start 0.67945 -0.305054)
			(end 0.12065 -0.305054)
			(stroke
				(width 0.1)
				(type default)
			)
			(layer "B.Fab")
		)
		(pad "1" smd circle
			(at 0.40005 0 90)
			(size 0 0)
			(layers "B.Cu" "B.Mask" "B.Paste")
			(net "SPI_BMC_BIOS_ROM_IO3")
		)
		(pad "2" smd circle
			(at -0.40005 0 90)
			(size 0 0)
			(layers "B.Cu" "B.Mask" "B.Paste")
			(net "SPI_BMC_BIOS_ROM_R_IO3")
		)
	)
	(footprint ""
		(layer "B.Cu")
		(at 25.019 -101.981 90)
		(property "Reference" "R575"
			(at 0 0 90)
			(layer "B.SilkS")
			(hide yes)
			(effects
				(font
					(size 1.27 1.27)
				)
				(justify mirror)
			)
		)
		(property "Value" ""
			(at 0 0 90)
			(layer "B.Fab")
			(effects
				(font
					(size 1.27 1.27)
				)
				(justify mirror)
			)
		)
		(duplicate_pad_numbers_are_jumpers no)
		(fp_line
			(start 0.7874 -0.4064)
			(end -0.7874 -0.4064)
			(stroke
				(width 0.1524)
				(type default)
			)
			(layer "B.SilkS")
		)
		(fp_line
			(start -0.7874 -0.4064)
			(end -0.7874 0.4064)
			(stroke
				(width 0.1524)
				(type default)
			)
			(layer "B.SilkS")
		)
		(fp_line
			(start 0.7874 0.4064)
			(end 0.7874 -0.4064)
			(stroke
				(width 0.1524)
				(type default)
			)
			(layer "B.SilkS")
		)
		(fp_line
			(start -0.7874 0.4064)
			(end 0.7874 0.4064)
			(stroke
				(width 0.1524)
				(type default)
			)
			(layer "B.SilkS")
		)
		(fp_line
			(start 0.67945 -0.305054)
			(end 0.12065 -0.305054)
			(stroke
				(width 0.1)
				(type default)
			)
			(layer "B.Fab")
		)
		(fp_line
			(start 0.12065 -0.305054)
			(end 0.12065 -0.2794)
			(stroke
				(width 0.1)
				(type default)
			)
			(layer "B.Fab")
		)
		(fp_line
			(start -0.12065 -0.3048)
			(end -0.67945 -0.3048)
			(stroke
				(width 0.1)
				(type default)
			)
			(layer "B.Fab")
		)
		(fp_line
			(start -0.67945 -0.3048)
			(end -0.67945 0.3048)
			(stroke
				(width 0.1)
				(type default)
			)
			(layer "B.Fab")
		)
		(fp_line
			(start 0.12065 -0.2794)
			(end -0.12065 -0.2794)
			(stroke
				(width 0.1)
				(type default)
			)
			(layer "B.Fab")
		)
		(fp_line
			(start -0.12065 -0.2794)
			(end -0.12065 -0.3048)
			(stroke
				(width 0.1)
				(type default)
			)
			(layer "B.Fab")
		)
		(fp_line
			(start 0.12065 0.2794)
			(end 0.12065 0.3048)
			(stroke
				(width 0.1)
				(type default)
			)
			(layer "B.Fab")
		)
		(fp_line
			(start -0.120396 0.2794)
			(end 0.12065 0.2794)
			(stroke
				(width 0.1)
				(type default)
			)
			(layer "B.Fab")
		)
		(fp_line
			(start 0.67945 0.3048)
			(end 0.67945 -0.305054)
			(stroke
				(width 0.1)
				(type default)
			)
			(layer "B.Fab")
		)
		(fp_line
			(start 0.12065 0.3048)
			(end 0.67945 0.3048)
			(stroke
				(width 0.1)
				(type default)
			)
			(layer "B.Fab")
		)
		(fp_line
			(start -0.120396 0.3048)
			(end -0.120396 0.2794)
			(stroke
				(width 0.1)
				(type default)
			)
			(layer "B.Fab")
		)
		(fp_line
			(start -0.67945 0.3048)
			(end -0.120396 0.3048)
			(stroke
				(width 0.1)
				(type default)
			)
			(layer "B.Fab")
		)
		(pad "1" smd circle
			(at 0.40005 0 270)
			(size 0 0)
			(layers "B.Cu" "B.Mask" "B.Paste")
			(net "FM_P12V_HSC_ENABLE")
		)
		(pad "2" smd circle
			(at -0.40005 0 270)
			(size 0 0)
			(layers "B.Cu" "B.Mask" "B.Paste")
			(net "FM_P12V_HSC_ENABLE_R2")
		)
	)
	(footprint ""
		(layer "B.Cu")
		(at 83.283552 -26.587704 180)
		(property "Reference" "R413"
			(at 0 0 0)
			(layer "B.SilkS")
			(hide yes)
			(effects
				(font
					(size 1.27 1.27)
				)
				(justify mirror)
			)
		)
		(property "Value" ""
			(at 0 0 0)
			(layer "B.Fab")
			(effects
				(font
					(size 1.27 1.27)
				)
				(justify mirror)
			)
		)
		(duplicate_pad_numbers_are_jumpers no)
		(fp_line
			(start 0.7874 0.4064)
			(end 0.7874 -0.4064)
			(stroke
				(width 0.1524)
				(type default)
			)
			(layer "B.SilkS")
		)
		(fp_line
			(start 0.7874 -0.4064)
			(end -0.7874 -0.4064)
			(stroke
				(width 0.1524)
				(type default)
			)
			(layer "B.SilkS")
		)
		(fp_line
			(start -0.7874 0.4064)
			(end 0.7874 0.4064)
			(stroke
				(width 0.1524)
				(type default)
			)
			(layer "B.SilkS")
		)
		(fp_line
			(start -0.7874 -0.4064)
			(end -0.7874 0.4064)
			(stroke
				(width 0.1524)
				(type default)
			)
			(layer "B.SilkS")
		)
		(fp_line
			(start 0.67945 0.3048)
			(end 0.67945 -0.305054)
			(stroke
				(width 0.1)
				(type default)
			)
			(layer "B.Fab")
		)
		(fp_line
			(start 0.67945 -0.305054)
			(end 0.12065 -0.305054)
			(stroke
				(width 0.1)
				(type default)
			)
			(layer "B.Fab")
		)
		(fp_line
			(start 0.12065 0.3048)
			(end 0.67945 0.3048)
			(stroke
				(width 0.1)
				(type default)
			)
			(layer "B.Fab")
		)
		(fp_line
			(start 0.12065 0.2794)
			(end 0.12065 0.3048)
			(stroke
				(width 0.1)
				(type default)
			)
			(layer "B.Fab")
		)
		(fp_line
			(start 0.12065 -0.2794)
			(end -0.12065 -0.2794)
			(stroke
				(width 0.1)
				(type default)
			)
			(layer "B.Fab")
		)
		(fp_line
			(start 0.12065 -0.305054)
			(end 0.12065 -0.2794)
			(stroke
				(width 0.1)
				(type default)
			)
			(layer "B.Fab")
		)
		(fp_line
			(start -0.120396 0.3048)
			(end -0.120396 0.2794)
			(stroke
				(width 0.1)
				(type default)
			)
			(layer "B.Fab")
		)
		(fp_line
			(start -0.120396 0.2794)
			(end 0.12065 0.2794)
			(stroke
				(width 0.1)
				(type default)
			)
			(layer "B.Fab")
		)
		(fp_line
			(start -0.12065 -0.2794)
			(end -0.12065 -0.3048)
			(stroke
				(width 0.1)
				(type default)
			)
			(layer "B.Fab")
		)
		(fp_line
			(start -0.12065 -0.3048)
			(end -0.67945 -0.3048)
			(stroke
				(width 0.1)
				(type default)
			)
			(layer "B.Fab")
		)
		(fp_line
			(start -0.67945 0.3048)
			(end -0.120396 0.3048)
			(stroke
				(width 0.1)
				(type default)
			)
			(layer "B.Fab")
		)
		(fp_line
			(start -0.67945 -0.3048)
			(end -0.67945 0.3048)
			(stroke
				(width 0.1)
				(type default)
			)
			(layer "B.Fab")
		)
		(pad "1" smd circle
			(at 0.40005 0)
			(size 0 0)
			(layers "B.Cu" "B.Mask" "B.Paste")
			(net "FRU_E2")
		)
		(pad "2" smd circle
			(at -0.40005 0)
			(size 0 0)
			(layers "B.Cu" "B.Mask" "B.Paste")
			(net "GND")
		)
	)
	(footprint ""
		(layer "B.Cu")
		(at 72.39 -19.685 90)
		(property "Reference" "R855"
			(at 0 0 90)
			(layer "B.SilkS")
			(hide yes)
			(effects
				(font
					(size 1.27 1.27)
				)
				(justify mirror)
			)
		)
		(property "Value" ""
			(at 0 0 90)
			(layer "B.Fab")
			(effects
				(font
					(size 1.27 1.27)
				)
				(justify mirror)
			)
		)
		(duplicate_pad_numbers_are_jumpers no)
		(fp_line
			(start 0.7874 -0.4064)
			(end -0.7874 -0.4064)
			(stroke
				(width 0.1524)
				(type default)
			)
			(layer "B.SilkS")
		)
		(fp_line
			(start -0.7874 -0.4064)
			(end -0.7874 0.4064)
			(stroke
				(width 0.1524)
				(type default)
			)
			(layer "B.SilkS")
		)
		(fp_line
			(start 0.7874 0.4064)
			(end 0.7874 -0.4064)
			(stroke
				(width 0.1524)
				(type default)
			)
			(layer "B.SilkS")
		)
		(fp_line
			(start -0.7874 0.4064)
			(end 0.7874 0.4064)
			(stroke
				(width 0.1524)
				(type default)
			)
			(layer "B.SilkS")
		)
		(fp_line
			(start 0.67945 -0.305054)
			(end 0.12065 -0.305054)
			(stroke
				(width 0.1)
				(type default)
			)
			(layer "B.Fab")
		)
		(fp_line
			(start 0.12065 -0.305054)
			(end 0.12065 -0.2794)
			(stroke
				(width 0.1)
				(type default)
			)
			(layer "B.Fab")
		)
		(fp_line
			(start -0.12065 -0.3048)
			(end -0.67945 -0.3048)
			(stroke
				(width 0.1)
				(type default)
			)
			(layer "B.Fab")
		)
		(fp_line
			(start -0.67945 -0.3048)
			(end -0.67945 0.3048)
			(stroke
				(width 0.1)
				(type default)
			)
			(layer "B.Fab")
		)
		(fp_line
			(start 0.12065 -0.2794)
			(end -0.12065 -0.2794)
			(stroke
				(width 0.1)
				(type default)
			)
			(layer "B.Fab")
		)
		(fp_line
			(start -0.12065 -0.2794)
			(end -0.12065 -0.3048)
			(stroke
				(width 0.1)
				(type default)
			)
			(layer "B.Fab")
		)
		(fp_line
			(start 0.12065 0.2794)
			(end 0.12065 0.3048)
			(stroke
				(width 0.1)
				(type default)
			)
			(layer "B.Fab")
		)
		(fp_line
			(start -0.120396 0.2794)
			(end 0.12065 0.2794)
			(stroke
				(width 0.1)
				(type default)
			)
			(layer "B.Fab")
		)
		(fp_line
			(start 0.67945 0.3048)
			(end 0.67945 -0.305054)
			(stroke
				(width 0.1)
				(type default)
			)
			(layer "B.Fab")
		)
		(fp_line
			(start 0.12065 0.3048)
			(end 0.67945 0.3048)
			(stroke
				(width 0.1)
				(type default)
			)
			(layer "B.Fab")
		)
		(fp_line
			(start -0.120396 0.3048)
			(end -0.120396 0.2794)
			(stroke
				(width 0.1)
				(type default)
			)
			(layer "B.Fab")
		)
		(fp_line
			(start -0.67945 0.3048)
			(end -0.120396 0.3048)
			(stroke
				(width 0.1)
				(type default)
			)
			(layer "B.Fab")
		)
		(pad "1" smd circle
			(at 0.40005 0 270)
			(size 0 0)
			(layers "B.Cu" "B.Mask" "B.Paste")
			(net "FM_BOARD_BMC_REV_ID2")
		)
		(pad "2" smd circle
			(at -0.40005 0 270)
			(size 0 0)
			(layers "B.Cu" "B.Mask" "B.Paste")
			(net "GND")
		)
	)
	(footprint ""
		(layer "B.Cu")
		(at 52.494688 -53.564536 -90)
		(property "Reference" "C66"
			(at 0 0 90)
			(layer "B.SilkS")
			(hide yes)
			(effects
				(font
					(size 1.27 1.27)
				)
				(justify mirror)
			)
		)
		(property "Value" ""
			(at 0 0 90)
			(layer "B.Fab")
			(effects
				(font
					(size 1.27 1.27)
				)
				(justify mirror)
			)
		)
		(duplicate_pad_numbers_are_jumpers no)
		(fp_line
			(start -0.7874 0.4064)
			(end 0.7874 0.4064)
			(stroke
				(width 0.1524)
				(type default)
			)
			(layer "B.SilkS")
		)
		(fp_line
			(start 0.7874 0.4064)
			(end 0.7874 -0.4064)
			(stroke
				(width 0.1524)
				(type default)
			)
			(layer "B.SilkS")
		)
		(fp_line
			(start -0.7874 -0.4064)
			(end -0.7874 0.4064)
			(stroke
				(width 0.1524)
				(type default)
			)
			(layer "B.SilkS")
		)
		(fp_line
			(start 0.7874 -0.4064)
			(end -0.7874 -0.4064)
			(stroke
				(width 0.1524)
				(type default)
			)
			(layer "B.SilkS")
		)
		(fp_line
			(start -0.67945 0.3048)
			(end -0.120396 0.3048)
			(stroke
				(width 0.1)
				(type default)
			)
			(layer "B.Fab")
		)
		(fp_line
			(start -0.120396 0.3048)
			(end -0.120396 0.2794)
			(stroke
				(width 0.1)
				(type default)
			)
			(layer "B.Fab")
		)
		(fp_line
			(start 0.12065 0.3048)
			(end 0.67945 0.3048)
			(stroke
				(width 0.1)
				(type default)
			)
			(layer "B.Fab")
		)
		(fp_line
			(start 0.67945 0.3048)
			(end 0.67945 -0.305054)
			(stroke
				(width 0.1)
				(type default)
			)
			(layer "B.Fab")
		)
		(fp_line
			(start -0.120396 0.2794)
			(end 0.12065 0.2794)
			(stroke
				(width 0.1)
				(type default)
			)
			(layer "B.Fab")
		)
		(fp_line
			(start 0.12065 0.2794)
			(end 0.12065 0.3048)
			(stroke
				(width 0.1)
				(type default)
			)
			(layer "B.Fab")
		)
		(fp_line
			(start -0.12065 -0.2794)
			(end -0.12065 -0.3048)
			(stroke
				(width 0.1)
				(type default)
			)
			(layer "B.Fab")
		)
		(fp_line
			(start 0.12065 -0.2794)
			(end -0.12065 -0.2794)
			(stroke
				(width 0.1)
				(type default)
			)
			(layer "B.Fab")
		)
		(fp_line
			(start -0.67945 -0.3048)
			(end -0.67945 0.3048)
			(stroke
				(width 0.1)
				(type default)
			)
			(layer "B.Fab")
		)
		(fp_line
			(start -0.12065 -0.3048)
			(end -0.67945 -0.3048)
			(stroke
				(width 0.1)
				(type default)
			)
			(layer "B.Fab")
		)
		(fp_line
			(start 0.12065 -0.305054)
			(end 0.12065 -0.2794)
			(stroke
				(width 0.1)
				(type default)
			)
			(layer "B.Fab")
		)
		(fp_line
			(start 0.67945 -0.305054)
			(end 0.12065 -0.305054)
			(stroke
				(width 0.1)
				(type default)
			)
			(layer "B.Fab")
		)
		(pad "1" smd circle
			(at 0.40005 0 90)
			(size 0 0)
			(layers "B.Cu" "B.Mask" "B.Paste")
			(net "P1V2_AUX")
		)
		(pad "2" smd circle
			(at -0.40005 0 90)
			(size 0 0)
			(layers "B.Cu" "B.Mask" "B.Paste")
			(net "GND")
		)
	)
)
